FILE_TYPE = CONNECTIVITY;
{Allegro Design Entry HDL 17.4-2019 S026 (4007227) 1/17/2022}
"PAGE_NUMBER" = 95;
0"NC";
1"GND\g";
2"GND\g";
3"P3V3\g";
4"M_K_CPU0_SA_CA<6:0>";
5"M_K_CPU0_SB_DQS_DP<9:0>";
6"M_K_CPU0_SB_DQS_DN<9:0>";
7"M_K_CPU0_SA_DQS_DP<9:0>";
8"M_K_CPU0_SA_DQS_DN<9:0>";
9"M_K_CPU0_SB_DQ<31:0>";
10"M_K_CPU0_SA_DQ<31:0>";
11"M_K_CPU0_SB_CB<7:0>";
12"M_K_CPU0_SA_CB<7:0>";
13"M_K_CPU0_SB_CA<6:0>";
14"M_K_CPU0_SB_CB<2>";
15"P3V3_AUX\g";
16"I3C_SPD_DDRGL_CPU0_SCL";
17"I3C_SPD_DDRGL_CPU0_SDA";
18"I3C_SPD_DDRK_CPU0_SDA";
19"I3C_SPD_DDRK_CPU0_SCL";
20"PWRGD_CHK_CPU0_DIMM";
21"PD_CHK_CPU0_DIMM_SAA";
22"M_K_CPU0_ALERT_N";
23"M_K_CPU0_RESET_N";
24"M_K_CPU0_SB_DQ<25>";
25"M_K_CPU0_SB_DQ<27>";
26"GND\g";
27"GND\g";
28"GND\g";
29"P12V_MEM_CPU0\g";
30"M_K_CPU0_SB_CB<0>";
31"M_K_CPU0_SB_CB<1>";
32"M_K_CPU0_SB_CB<4>";
33"M_K_CPU0_SB_CB<5>";
34"M_K_CPU0_SA_CB<0>";
35"PD_CHK_CPU0_DIMM_SAA";
36"M_K_CPU0_SA_DQ<31>";
37"M_K_CPU0_SA_CB<7>";
38"M_K_CPU0_SA_CB<4>";
39"M_K_CPU0_SA_CB<1>";
40"M_K_CPU0_SB_CB<7>";
41"M_K_CPU0_SA_CA<0>";
42"M_K_CPU0_SB_CA<0>";
43"M_K_CPU0_SA_CA<1>";
44"M_K_CPU0_SB_CA<1>";
45"M_K_CPU0_SA_CA<2>";
46"M_K_CPU0_SB_CA<2>";
47"M_K_CPU0_SB_CA<3>";
48"M_K_CPU0_SB_CA<4>";
49"M_K_CPU0_SB_CA<5>";
50"M_K_CPU0_SB_CA<6>";
51"M_K_CPU0_SA_CB<6>";
52"M_K_CPU0_SA_CB<5>";
53"M_K_CPU0_SA_CB<3>";
54"M_K_CPU0_SA_CB<2>";
55"M_K_CPU0_SB_CB<6>";
56"M_K_CPU0_SB_CB<3>";
57"M_K_CPU0_SB_CS_N<0>";
58"M_K_CPU0_SB_CS_N<1>";
59"M_K_CPU0_SA_DQ<30>";
60"M_K_CPU0_SA_DQ<29>";
61"M_K_CPU0_SA_DQ<28>";
62"M_K_CPU0_SA_DQ<27>";
63"M_K_CPU0_SA_DQ<26>";
64"M_K_CPU0_SA_DQ<25>";
65"M_K_CPU0_SA_DQ<24>";
66"M_K_CPU0_SA_DQ<23>";
67"M_K_CPU0_SA_DQ<22>";
68"M_K_CPU0_SA_DQ<21>";
69"M_K_CPU0_SA_DQ<20>";
70"M_K_CPU0_SA_DQ<19>";
71"M_K_CPU0_SA_DQ<18>";
72"M_K_CPU0_SA_DQ<17>";
73"M_K_CPU0_SA_DQ<16>";
74"M_K_CPU0_SA_DQ<15>";
75"M_K_CPU0_SA_DQ<14>";
76"M_K_CPU0_SA_DQ<13>";
77"M_K_CPU0_SA_DQ<12>";
78"M_K_CPU0_SA_DQ<11>";
79"M_K_CPU0_SA_DQ<10>";
80"M_K_CPU0_SA_DQ<9>";
81"M_K_CPU0_SA_DQ<8>";
82"M_K_CPU0_SA_DQ<7>";
83"M_K_CPU0_SA_DQ<6>";
84"M_K_CPU0_SA_DQ<5>";
85"M_K_CPU0_SA_DQ<4>";
86"M_K_CPU0_SA_DQ<3>";
87"M_K_CPU0_SA_DQ<2>";
88"M_K_CPU0_SA_DQ<1>";
89"M_K_CPU0_SA_DQ<0>";
90"M_K_CPU0_SB_DQ<31>";
91"M_K_CPU0_SB_DQ<30>";
92"M_K_CPU0_SB_DQ<29>";
93"M_K_CPU0_SB_DQ<28>";
94"M_K_CPU0_SB_DQ<26>";
95"M_K_CPU0_SB_DQ<24>";
96"M_K_CPU0_SB_DQ<23>";
97"M_K_CPU0_SB_DQ<22>";
98"M_K_CPU0_SB_DQ<21>";
99"M_K_CPU0_SB_DQ<20>";
100"M_K_CPU0_SB_DQ<19>";
101"M_K_CPU0_SB_DQ<18>";
102"M_K_CPU0_SB_DQ<17>";
103"M_K_CPU0_SB_DQ<16>";
104"M_K_CPU0_SB_DQ<15>";
105"M_K_CPU0_SB_DQ<14>";
106"M_K_CPU0_SB_DQ<13>";
107"M_K_CPU0_SB_DQ<12>";
108"M_K_CPU0_SB_DQ<11>";
109"M_K_CPU0_SB_DQ<10>";
110"M_K_CPU0_SB_DQ<9>";
111"M_K_CPU0_SB_DQ<8>";
112"M_K_CPU0_SB_DQ<7>";
113"M_K_CPU0_SB_DQ<6>";
114"M_K_CPU0_SB_DQ<5>";
115"M_K_CPU0_SB_DQ<4>";
116"M_K_CPU0_SB_DQ<3>";
117"M_K_CPU0_SB_DQ<2>";
118"M_K_CPU0_SB_DQ<1>";
119"M_K_CPU0_SB_DQ<0>";
120"M_K_CPU0_SA_PAR";
121"M_K_CPU0_SB_PAR";
122"M_K_CPU0_SA_DQS_DN<7>";
123"M_K_CPU0_SA_DQS_DP<6>";
124"M_K_CPU0_SB_DQS_DP<8>";
125"M_K_CPU0_SB_DQS_DN<8>";
126"M_K_CPU0_SB_DQS_DP<7>";
127"M_K_CPU0_SA_DQS_DN<0>";
128"M_K_CPU0_SA_DQS_DP<0>";
129"M_K_CPU0_SB_DQS_DN<0>";
130"M_K_CPU0_SB_DQS_DP<0>";
131"M_K_CPU0_SA_DQS_DN<1>";
132"M_K_CPU0_SA_DQS_DP<1>";
133"M_K_CPU0_SB_DQS_DN<1>";
134"M_K_CPU0_SB_DQS_DP<1>";
135"M_K_CPU0_SA_DQS_DN<2>";
136"M_K_CPU0_SA_DQS_DP<2>";
137"M_K_CPU0_SB_DQS_DN<2>";
138"M_K_CPU0_SB_DQS_DP<2>";
139"M_K_CPU0_SA_DQS_DN<3>";
140"M_K_CPU0_SA_DQS_DP<3>";
141"M_K_CPU0_SB_DQS_DN<3>";
142"M_K_CPU0_SB_DQS_DP<3>";
143"M_K_CPU0_SA_DQS_DN<4>";
144"M_K_CPU0_SA_DQS_DP<4>";
145"M_K_CPU0_SB_DQS_DN<4>";
146"M_K_CPU0_SB_DQS_DP<4>";
147"M_K_CPU0_SA_DQS_DN<5>";
148"M_K_CPU0_SA_DQS_DP<5>";
149"M_K_CPU0_SB_DQS_DN<5>";
150"M_K_CPU0_SB_DQS_DP<5>";
151"M_K_CPU0_SA_DQS_DN<6>";
152"M_K_CPU0_SB_DQS_DN<6>";
153"M_K_CPU0_SB_DQS_DP<6>";
154"M_K_CPU0_SA_DQS_DP<7>";
155"M_K_CPU0_SB_DQS_DN<7>";
156"M_K_CPU0_SA_DQS_DN<8>";
157"M_K_CPU0_SA_DQS_DP<8>";
158"M_K_CPU0_SA_DQS_DN<9>";
159"M_K_CPU0_SA_DQS_DP<9>";
160"M_K_CPU0_SB_DQS_DN<9>";
161"M_K_CPU0_SB_DQS_DP<9>";
162"M_K_CPU0_SA_CA<3>";
163"M_K_CPU0_SA_CA<4>";
164"M_K_CPU0_SA_CA<5>";
165"M_K_CPU0_SA_CA<6>";
166"M_K_CPU0_SA_CS_N<1>";
167"M_K_CPU0_SA_CS_N<0>";
168"M_K_CPU0_SB_RSP<0>";
169"M_K_CPU0_CLK_DP<0>";
170"M_K_CPU0_CLK_DN<0>";
171"M_K_CPU0_SA_RSP<0>";
172"PWRGD_CHGL_CPU0";
%"TAP"
"1","(-6025,4125)","0","mstr_standard","I100";
;
CDS_LIB"mstr_standard"
BODY_TYPE"PLUMBING"
HDL_TAP"TRUE";
"B \NAC \NWC"10;
"S \NAC"
BN"6"83;
%"TAP"
"1","(-6025,4175)","0","mstr_standard","I101";
;
CDS_LIB"mstr_standard"
BODY_TYPE"PLUMBING"
HDL_TAP"TRUE";
"B \NAC \NWC"10;
"S \NAC"
BN"7"82;
%"TAP"
"1","(-6025,4225)","0","mstr_standard","I102";
;
CDS_LIB"mstr_standard"
BODY_TYPE"PLUMBING"
HDL_TAP"TRUE";
"B \NAC \NWC"10;
"S \NAC"
BN"8"81;
%"TAP"
"1","(-6025,4275)","0","mstr_standard","I103";
;
CDS_LIB"mstr_standard"
BODY_TYPE"PLUMBING"
HDL_TAP"TRUE";
"B \NAC \NWC"10;
"S \NAC"
BN"9"80;
%"TAP"
"1","(-6025,4325)","0","mstr_standard","I104";
;
CDS_LIB"mstr_standard"
BODY_TYPE"PLUMBING"
HDL_TAP"TRUE";
"B \NAC \NWC"10;
"S \NAC"
BN"10"79;
%"TAP"
"1","(-6025,4425)","0","mstr_standard","I105";
;
CDS_LIB"mstr_standard"
BODY_TYPE"PLUMBING"
HDL_TAP"TRUE";
"B \NAC \NWC"10;
"S \NAC"
BN"12"77;
%"TAP"
"1","(-6025,4375)","0","mstr_standard","I106";
;
CDS_LIB"mstr_standard"
BODY_TYPE"PLUMBING"
HDL_TAP"TRUE";
"B \NAC \NWC"10;
"S \NAC"
BN"11"78;
%"TAP"
"1","(-6025,4475)","0","mstr_standard","I107";
;
CDS_LIB"mstr_standard"
BODY_TYPE"PLUMBING"
HDL_TAP"TRUE";
"B \NAC \NWC"10;
"S \NAC"
BN"13"76;
%"TAP"
"1","(-6025,4525)","0","mstr_standard","I108";
;
CDS_LIB"mstr_standard"
BODY_TYPE"PLUMBING"
HDL_TAP"TRUE";
"B \NAC \NWC"10;
"S \NAC"
BN"14"75;
%"TAP"
"1","(-6025,4575)","0","mstr_standard","I109";
;
CDS_LIB"mstr_standard"
BODY_TYPE"PLUMBING"
HDL_TAP"TRUE";
"B \NAC \NWC"10;
"S \NAC"
BN"15"74;
%"TAP"
"1","(-6025,4625)","0","mstr_standard","I110";
;
CDS_LIB"mstr_standard"
BODY_TYPE"PLUMBING"
HDL_TAP"TRUE";
"B \NAC \NWC"10;
"S \NAC"
BN"16"73;
%"TAP"
"1","(-6025,4675)","0","mstr_standard","I111";
;
CDS_LIB"mstr_standard"
BODY_TYPE"PLUMBING"
HDL_TAP"TRUE";
"B \NAC \NWC"10;
"S \NAC"
BN"17"72;
%"TAP"
"1","(-6025,4725)","0","mstr_standard","I112";
;
CDS_LIB"mstr_standard"
BODY_TYPE"PLUMBING"
HDL_TAP"TRUE";
"B \NAC \NWC"10;
"S \NAC"
BN"18"71;
%"TAP"
"1","(-6025,4775)","0","mstr_standard","I113";
;
CDS_LIB"mstr_standard"
BODY_TYPE"PLUMBING"
HDL_TAP"TRUE";
"B \NAC \NWC"10;
"S \NAC"
BN"19"70;
%"TAP"
"1","(-6025,4825)","0","mstr_standard","I114";
;
CDS_LIB"mstr_standard"
BODY_TYPE"PLUMBING"
HDL_TAP"TRUE";
"B \NAC \NWC"10;
"S \NAC"
BN"20"69;
%"TAP"
"1","(-6025,4875)","0","mstr_standard","I115";
;
CDS_LIB"mstr_standard"
BODY_TYPE"PLUMBING"
HDL_TAP"TRUE";
"B \NAC \NWC"10;
"S \NAC"
BN"21"68;
%"TAP"
"1","(-6025,4925)","0","mstr_standard","I116";
;
CDS_LIB"mstr_standard"
BODY_TYPE"PLUMBING"
HDL_TAP"TRUE";
"B \NAC \NWC"10;
"S \NAC"
BN"22"67;
%"TAP"
"1","(-6025,4975)","0","mstr_standard","I117";
;
CDS_LIB"mstr_standard"
BODY_TYPE"PLUMBING"
HDL_TAP"TRUE";
"B \NAC \NWC"10;
"S \NAC"
BN"23"66;
%"TAP"
"1","(-6025,5025)","0","mstr_standard","I118";
;
CDS_LIB"mstr_standard"
BODY_TYPE"PLUMBING"
HDL_TAP"TRUE";
"B \NAC \NWC"10;
"S \NAC"
BN"24"65;
%"TAP"
"1","(-6025,5075)","0","mstr_standard","I119";
;
CDS_LIB"mstr_standard"
BODY_TYPE"PLUMBING"
HDL_TAP"TRUE";
"B \NAC \NWC"10;
"S \NAC"
BN"25"64;
%"TAP"
"1","(-6025,5125)","0","mstr_standard","I120";
;
CDS_LIB"mstr_standard"
BODY_TYPE"PLUMBING"
HDL_TAP"TRUE";
"B \NAC \NWC"10;
"S \NAC"
BN"26"63;
%"TAP"
"1","(-6025,5175)","0","mstr_standard","I121";
;
CDS_LIB"mstr_standard"
BODY_TYPE"PLUMBING"
HDL_TAP"TRUE";
"B \NAC \NWC"10;
"S \NAC"
BN"27"62;
%"TAP"
"1","(-6025,5225)","0","mstr_standard","I122";
;
CDS_LIB"mstr_standard"
BODY_TYPE"PLUMBING"
HDL_TAP"TRUE";
"B \NAC \NWC"10;
"S \NAC"
BN"28"61;
%"TAP"
"1","(-6025,5325)","0","mstr_standard","I123";
;
CDS_LIB"mstr_standard"
BODY_TYPE"PLUMBING"
HDL_TAP"TRUE";
"B \NAC \NWC"10;
"S \NAC"
BN"30"59;
%"TAP"
"1","(-6025,5275)","0","mstr_standard","I124";
;
CDS_LIB"mstr_standard"
BODY_TYPE"PLUMBING"
HDL_TAP"TRUE";
"B \NAC \NWC"10;
"S \NAC"
BN"29"60;
%"TAP"
"1","(-6025,5375)","0","mstr_standard","I125";
;
CDS_LIB"mstr_standard"
BODY_TYPE"PLUMBING"
HDL_TAP"TRUE";
"B \NAC \NWC"10;
"S \NAC"
BN"31"36;
%"GND"
"1","(-6425,1050)","0","mstr_symbols","I128";
;
CDS_LIB"mstr_symbols"
BOM_COST"MEM"
SIZE"1B"
VOLTAGE"0.0"
BODY_TYPE"PLUMBING"
HDL_POWER"GND";
"A\NAC"1;
%"Q_RES"
"2","(-6425,1275)","0","pure_quanta","I129";
;
LOCATION"R768"
$SEC"1"
CDS_SEC"1"
PACK_TYPE"0402LF"
VALUE"54.9K"
TOLERANCE"1%"
MATERIAL"CHIP"
WATTAGE"1/16W"
CDS_LIB"pure_quanta"
PART_NUMBER"CS35492FB03";
"A"
$PN"1"35;
"B"
$PN"2"1;
%"GND"
"1","(-2125,1900)","0","mstr_symbols","I130";
;
SIZE"1B"
CDS_LIB"mstr_symbols"
VOLTAGE"0.0"
BODY_TYPE"PLUMBING"
HDL_POWER"GND";
"A\NAC"26;
%"GND"
"1","(-325,1675)","0","mstr_symbols","I144";
;
SIZE"1B"
CDS_LIB"mstr_symbols"
VOLTAGE"0.0"
BODY_TYPE"PLUMBING"
HDL_POWER"GND";
"A\NAC"27;
%"SCONN288_DDR506112002KQ"
"3","(-1225,3675)","0","pure_quanta","I177";
;
LOCATION"J20"
$SEC"3"
CDS_SEC"3"
PART_TYPE"SMLF"
VALUE"SCONN288_DDR506112002KQ"
MATERIAL"IO"
CDS_LMAN_SYM_OUTLINE"-450,1800,450,-1750"
NEEDS_NO_SIZE"TRUE"
CDS_LIB"pure_quanta"
PART_NUMBER"DFHST8FS479";
"G3"
$PN"G3"27;
"G2"
$PN"G2"27;
"G1"
$PN"G1"27;
"VSS62"
$PN"141"27;
"VSS61"
$PN"139"27;
"VSS60"
$PN"136"27;
"VSS58"
$PN"132"27;
"VSS104"
$PN"240"26;
"VSS102"
$PN"235"26;
"VSS100"
$PN"230"26;
"VIN_BULK2"
$PN"146"29;
"VIN_BULK1"
$PN"145"29;
"VIN_BULK0"
$PN"1"29;
"VSS126"
$PN"288"26;
"VSS125"
$PN"286"26;
"VSS124"
$PN"284"26;
"VSS123"
$PN"281"26;
"VSS122"
$PN"279"26;
"VSS121"
$PN"277"26;
"VSS120"
$PN"275"26;
"VSS119"
$PN"273"26;
"VSS118"
$PN"270"26;
"VSS117"
$PN"268"26;
"VSS116"
$PN"266"26;
"VSS115"
$PN"264"26;
"VSS114"
$PN"262"26;
"VSS113"
$PN"259"26;
"VSS112"
$PN"257"26;
"VSS111"
$PN"255"26;
"VSS110"
$PN"253"26;
"VSS109"
$PN"251"26;
"VSS108"
$PN"248"26;
"VSS107"
$PN"246"26;
"VSS106"
$PN"244"26;
"VSS105"
$PN"242"26;
"VSS103"
$PN"237"26;
"VSS101"
$PN"233"26;
"VSS99"
$PN"228"26;
"VSS98"
$PN"226"26;
"VSS97"
$PN"224"26;
"VSS96"
$PN"222"26;
"VSS95"
$PN"219"26;
"VSS94"
$PN"216"26;
"VSS93"
$PN"214"26;
"VSS92"
$PN"212"26;
"VSS91"
$PN"210"26;
"VSS90"
$PN"208"26;
"VSS89"
$PN"206"26;
"VSS88"
$PN"204"26;
"VSS87"
$PN"202"26;
"VSS86"
$PN"199"26;
"VSS85"
$PN"197"26;
"VSS84"
$PN"195"26;
"VSS83"
$PN"193"26;
"VSS82"
$PN"191"26;
"VSS81"
$PN"188"26;
"VSS80"
$PN"186"26;
"VSS79"
$PN"184"26;
"VSS78"
$PN"182"26;
"VSS77"
$PN"180"26;
"VSS76"
$PN"177"26;
"VSS75"
$PN"175"26;
"VSS74"
$PN"173"26;
"VSS73"
$PN"171"26;
"VSS72"
$PN"169"26;
"VSS71"
$PN"166"26;
"VSS70"
$PN"164"26;
"VSS69"
$PN"162"26;
"VSS68"
$PN"160"26;
"VSS67"
$PN"158"26;
"VSS66"
$PN"155"26;
"VSS65"
$PN"153"26;
"VSS64"
$PN"151"26;
"VSS63"
$PN"143"27;
"VSS59"
$PN"134"27;
"VSS57"
$PN"130"27;
"VSS56"
$PN"128"27;
"VSS55"
$PN"125"27;
"VSS54"
$PN"123"27;
"VSS53"
$PN"121"27;
"VSS52"
$PN"119"27;
"VSS51"
$PN"117"27;
"VSS50"
$PN"114"27;
"VSS49"
$PN"112"27;
"VSS48"
$PN"110"27;
"VSS47"
$PN"108"27;
"VSS46"
$PN"106"27;
"VSS45"
$PN"103"27;
"VSS44"
$PN"101"27;
"VSS43"
$PN"99"27;
"VSS42"
$PN"97"27;
"VSS41"
$PN"95"27;
"VSS40"
$PN"92"27;
"VSS39"
$PN"90"27;
"VSS38"
$PN"88"27;
"VSS37"
$PN"85"27;
"VSS36"
$PN"83"27;
"VSS35"
$PN"81"27;
"VSS34"
$PN"79"27;
"VSS33"
$PN"77"27;
"VSS32"
$PN"75"27;
"VSS31"
$PN"73"27;
"VSS30"
$PN"71"27;
"VSS29"
$PN"69"27;
"VSS28"
$PN"67"27;
"VSS27"
$PN"65"27;
"VSS26"
$PN"63"27;
"VSS25"
$PN"61"27;
"VSS24"
$PN"59"27;
"VSS23"
$PN"57"27;
"VSS22"
$PN"54"27;
"VSS21"
$PN"52"27;
"VSS20"
$PN"50"27;
"VSS19"
$PN"48"27;
"VSS18"
$PN"46"27;
"VSS17"
$PN"43"27;
"VSS16"
$PN"41"27;
"VSS15"
$PN"39"27;
"VSS14"
$PN"37"27;
"VSS13"
$PN"35"27;
"VSS12"
$PN"32"27;
"VSS11"
$PN"30"27;
"VSS10"
$PN"28"27;
"VSS9"
$PN"26"27;
"VSS8"
$PN"24"27;
"VSS7"
$PN"21"27;
"VSS6"
$PN"19"27;
"VSS5"
$PN"17"27;
"VSS4"
$PN"15"27;
"VSS3"
$PN"13"27;
"VSS2"
$PN"10"27;
"VSS1"
$PN"8"27;
"VSS0"
$PN"6"27;
%"Q_CAP"
"1","(-8600,3200)","2","pure_quanta","I185";
;
LOCATION"C128"
$SEC"1"
CDS_SEC"1"
VALUE"0.1UF"
VOLTAGE"25V"
PACK_TYPE"0402"
TOLERANCE"10%"
MATERIAL"X7R"
CDS_LIB"pure_quanta"
BOM_COST"MEM"
ROOM""
PART_NUMBER"CH4104K1B00";
"B"
$PN"2"2;
"A"
$PN"1"15;
%"GND"
"1","(-8600,2975)","0","mstr_symbols","I186";
;
BOM_COST"MEM"
SIZE"1B"
CDS_LIB"mstr_symbols"
VOLTAGE"0"
ROOM"MEM_EFGH_DECOUPLING_CAPS"
BODY_TYPE"PLUMBING"
HDL_POWER"GND";
"A\NAC"2;
%"Q_RES"
"1","(-8475,2125)","2","pure_quanta","I188";
;
LOCATION"R301"
$SEC"1"
CDS_SEC"1"
VALUE"1K"
TOLERANCE"1%"
CDS_LIB"pure_quanta"
BOM_COST"MEM"
WATTAGE"1/16W"
MATERIAL"CHIP"
PACK_TYPE"0402LF"
ROOM""
PART_NUMBER"CS21002FB06";
"B"
$PN"2"172;
"A"
$PN"1"20;
%"Q_RES"
"2","(-8350,2275)","0","pure_quanta","I189";
;
LOCATION"R100"
$SEC"1"
CDS_SEC"1"
TOLERANCE"1%"
VALUE"1K"
PACK_TYPE"0402LF"
MATERIAL"EMPTY"
WATTAGE"1/16W"
CDS_LIB"pure_quanta"
BOM_COST"MEM"
ROOM""
PART_NUMBER"CS21002FB06";
"A"
$PN"1"3;
"B"
$PN"2"20;
%"VCC_CORE"
"1","(-8350,2450)","0","mstr_symbols","I190";
;
HDL_POWER"P3V3"
CDS_LIB"mstr_symbols"
VOLTAGE"3.3"
ROOM"PVCCINFAON_CPU0_CTRL";
"A"3;
%"TAP"
"1","(-3275,3200)","0","mstr_standard","I191";
;
CDS_LIB"mstr_standard"
BODY_TYPE"PLUMBING"
HDL_TAP"TRUE";
"B \NAC \NWC"6;
"S \NAC"
BN"6"152;
%"TAP"
"1","(-3475,3250)","0","mstr_standard","I192";
;
CDS_LIB"mstr_standard"
BODY_TYPE"PLUMBING"
HDL_TAP"TRUE";
"B \NAC \NWC"5;
"S \NAC"
BN"6"153;
%"TAP"
"1","(-3475,3350)","0","mstr_standard","I193";
;
CDS_LIB"mstr_standard"
BODY_TYPE"PLUMBING"
HDL_TAP"TRUE";
"B \NAC \NWC"5;
"S \NAC"
BN"7"126;
%"TAP"
"1","(-3275,4550)","0","mstr_standard","I199";
;
CDS_LIB"mstr_standard"
BODY_TYPE"PLUMBING"
HDL_TAP"TRUE";
"B \NAC \NWC"8;
"S \NAC"
BN"9"158;
%"TAP"
"1","(-3275,4450)","0","mstr_standard","I200";
;
CDS_LIB"mstr_standard"
BODY_TYPE"PLUMBING"
HDL_TAP"TRUE";
"B \NAC \NWC"8;
"S \NAC"
BN"8"156;
%"TAP"
"1","(-3475,4600)","0","mstr_standard","I201";
;
CDS_LIB"mstr_standard"
BODY_TYPE"PLUMBING"
HDL_TAP"TRUE";
"B \NAC \NWC"7;
"S \NAC"
BN"9"159;
%"TAP"
"1","(-3475,4400)","0","mstr_standard","I202";
;
CDS_LIB"mstr_standard"
BODY_TYPE"PLUMBING"
HDL_TAP"TRUE";
"B \NAC \NWC"7;
"S \NAC"
BN"7"154;
%"TAP"
"1","(-3475,4500)","0","mstr_standard","I203";
;
CDS_LIB"mstr_standard"
BODY_TYPE"PLUMBING"
HDL_TAP"TRUE";
"B \NAC \NWC"7;
"S \NAC"
BN"8"157;
%"TAP"
"1","(-3275,4350)","0","mstr_standard","I204";
;
CDS_LIB"mstr_standard"
BODY_TYPE"PLUMBING"
HDL_TAP"TRUE";
"B \NAC \NWC"8;
"S \NAC"
BN"7"122;
%"TAP"
"1","(-3275,4150)","0","mstr_standard","I205";
;
CDS_LIB"mstr_standard"
BODY_TYPE"PLUMBING"
HDL_TAP"TRUE";
"B \NAC \NWC"8;
"S \NAC"
BN"5"147;
%"TAP"
"1","(-3275,4250)","0","mstr_standard","I206";
;
CDS_LIB"mstr_standard"
BODY_TYPE"PLUMBING"
HDL_TAP"TRUE";
"B \NAC \NWC"8;
"S \NAC"
BN"6"151;
%"TAP"
"1","(-3275,4050)","0","mstr_standard","I207";
;
CDS_LIB"mstr_standard"
BODY_TYPE"PLUMBING"
HDL_TAP"TRUE";
"B \NAC \NWC"8;
"S \NAC"
BN"4"143;
%"TAP"
"1","(-3275,3950)","0","mstr_standard","I208";
;
CDS_LIB"mstr_standard"
BODY_TYPE"PLUMBING"
HDL_TAP"TRUE";
"B \NAC \NWC"8;
"S \NAC"
BN"3"139;
%"TAP"
"1","(-3275,3850)","0","mstr_standard","I209";
;
CDS_LIB"mstr_standard"
BODY_TYPE"PLUMBING"
HDL_TAP"TRUE";
"B \NAC \NWC"8;
"S \NAC"
BN"2"135;
%"TAP"
"1","(-3275,3650)","0","mstr_standard","I210";
;
CDS_LIB"mstr_standard"
BODY_TYPE"PLUMBING"
HDL_TAP"TRUE";
"B \NAC \NWC"8;
"S \NAC"
BN"0"127;
%"TAP"
"1","(-3275,3750)","0","mstr_standard","I211";
;
CDS_LIB"mstr_standard"
BODY_TYPE"PLUMBING"
HDL_TAP"TRUE";
"B \NAC \NWC"8;
"S \NAC"
BN"1"131;
%"TAP"
"1","(-3275,3500)","0","mstr_standard","I212";
;
CDS_LIB"mstr_standard"
BODY_TYPE"PLUMBING"
HDL_TAP"TRUE";
"B \NAC \NWC"6;
"S \NAC"
BN"9"160;
%"TAP"
"1","(-3275,3400)","0","mstr_standard","I213";
;
CDS_LIB"mstr_standard"
BODY_TYPE"PLUMBING"
HDL_TAP"TRUE";
"B \NAC \NWC"6;
"S \NAC"
BN"8"125;
%"TAP"
"1","(-3475,4300)","0","mstr_standard","I214";
;
CDS_LIB"mstr_standard"
BODY_TYPE"PLUMBING"
HDL_TAP"TRUE";
"B \NAC \NWC"7;
"S \NAC"
BN"6"123;
%"TAP"
"1","(-3475,4200)","0","mstr_standard","I215";
;
CDS_LIB"mstr_standard"
BODY_TYPE"PLUMBING"
HDL_TAP"TRUE";
"B \NAC \NWC"7;
"S \NAC"
BN"5"148;
%"TAP"
"1","(-3475,4100)","0","mstr_standard","I216";
;
CDS_LIB"mstr_standard"
BODY_TYPE"PLUMBING"
HDL_TAP"TRUE";
"B \NAC \NWC"7;
"S \NAC"
BN"4"144;
%"TAP"
"1","(-3475,3900)","0","mstr_standard","I217";
;
CDS_LIB"mstr_standard"
BODY_TYPE"PLUMBING"
HDL_TAP"TRUE";
"B \NAC \NWC"7;
"S \NAC"
BN"2"136;
%"TAP"
"1","(-3475,4000)","0","mstr_standard","I218";
;
CDS_LIB"mstr_standard"
BODY_TYPE"PLUMBING"
HDL_TAP"TRUE";
"B \NAC \NWC"7;
"S \NAC"
BN"3"140;
%"TAP"
"1","(-3475,3800)","0","mstr_standard","I219";
;
CDS_LIB"mstr_standard"
BODY_TYPE"PLUMBING"
HDL_TAP"TRUE";
"B \NAC \NWC"7;
"S \NAC"
BN"1"132;
%"SCONN288_DDR506112002KQ"
"1","(-6875,3625)","0","pure_quanta","I22";
;
LOCATION"J20"
$SEC"1"
CDS_SEC"1"
PART_TYPE"SMLF"
VALUE"SCONN288_DDR506112002KQ"
MATERIAL"IO"
CDS_LMAN_SYM_OUTLINE"-450,1900,450,-1850"
NEEDS_NO_SIZE"TRUE"
CDS_LIB"pure_quanta"
PART_NUMBER"DFHST8FS479";
"PWR_GOOD||FAIL_N"
$PN"147"20;
"DQ31_A"
$PN"194"36;
"CB7_A"
$PN"205"37;
"CB4_A"
$PN"58"38;
"CB1_A"
$PN"53"39;
"CB7_B"
$PN"236"40;
"ALERT_N \B"
$PN"62"22;
"CA0_A"
$PN"66"41;
"CA0_B"
$PN"76"42;
"CA1_A"
$PN"211"43;
"CA1_B"
$PN"221"44;
"CA2_A"
$PN"68"45;
"CA2_B"
$PN"78"46;
"CA3_A"
$PN"213"162;
"CA3_B"
$PN"223"47;
"CA4_A"
$PN"70"163;
"CA4_B"
$PN"80"48;
"CA5_A"
$PN"215"164;
"CA5_B"
$PN"225"49;
"CA6_A"
$PN"72"165;
"CA6_B"
$PN"82"50;
"CB6_A"
$PN"203"51;
"CB5_A"
$PN"60"52;
"CB3_A"
$PN"198"53;
"CB2_A"
$PN"196"54;
"CB0_A"
$PN"51"34;
"CB6_B"
$PN"234"55;
"CB5_B"
$PN"91"33;
"CB4_B"
$PN"89"32;
"CB3_B"
$PN"243"56;
"CB2_B"
$PN"241"14;
"CB1_B"
$PN"98"31;
"CB0_B"
$PN"96"30;
"CK_C \B"
$PN"218"170;
"CK_T"
$PN"217"169;
"CS0_A_N"
$PN"64"167;
"CS0_B_N"
$PN"84"57;
"CS1_A_N"
$PN"209"166;
"CS1_B_N"
$PN"229"58;
"DQ30_A"
$PN"192"59;
"DQ29_A"
$PN"49"60;
"DQ28_A"
$PN"47"61;
"DQ27_A"
$PN"187"62;
"DQ26_A"
$PN"185"63;
"DQ25_A"
$PN"42"64;
"DQ24_A"
$PN"40"65;
"DQ23_A"
$PN"183"66;
"DQ22_A"
$PN"181"67;
"DQ21_A"
$PN"38"68;
"DQ20_A"
$PN"36"69;
"DQ19_A"
$PN"176"70;
"DQ18_A"
$PN"174"71;
"DQ17_A"
$PN"31"72;
"DQ16_A"
$PN"29"73;
"DQ15_A"
$PN"172"74;
"DQ14_A"
$PN"170"75;
"DQ13_A"
$PN"27"76;
"DQ12_A"
$PN"25"77;
"DQ11_A"
$PN"165"78;
"DQ10_A"
$PN"163"79;
"DQ9_A"
$PN"20"80;
"DQ8_A"
$PN"18"81;
"DQ7_A"
$PN"161"82;
"DQ6_A"
$PN"159"83;
"DQ5_A"
$PN"16"84;
"DQ4_A"
$PN"14"85;
"DQ3_A"
$PN"154"86;
"DQ2_A"
$PN"152"87;
"DQ1_A"
$PN"9"88;
"DQ0_A"
$PN"7"89;
"DQ31_B"
$PN"287"90;
"DQ30_B"
$PN"285"91;
"DQ29_B"
$PN"142"92;
"DQ28_B"
$PN"140"93;
"DQ27_B"
$PN"280"25;
"DQ26_B"
$PN"278"94;
"DQ25_B"
$PN"135"24;
"DQ24_B"
$PN"133"95;
"DQ23_B"
$PN"276"96;
"DQ22_B"
$PN"274"97;
"DQ21_B"
$PN"131"98;
"DQ20_B"
$PN"129"99;
"DQ19_B"
$PN"269"100;
"DQ18_B"
$PN"267"101;
"DQ17_B"
$PN"124"102;
"DQ16_B"
$PN"122"103;
"DQ15_B"
$PN"265"104;
"DQ14_B"
$PN"263"105;
"DQ13_B"
$PN"120"106;
"DQ12_B"
$PN"118"107;
"DQ11_B"
$PN"258"108;
"DQ10_B"
$PN"256"109;
"DQ9_B"
$PN"113"110;
"DQ8_B"
$PN"111"111;
"DQ7_B"
$PN"254"112;
"DQ6_B"
$PN"252"113;
"DQ5_B"
$PN"109"114;
"DQ4_B"
$PN"107"115;
"DQ3_B"
$PN"247"116;
"DQ2_B"
$PN"245"117;
"DQ1_B"
$PN"102"118;
"DQ0_B"
$PN"100"119;
"HAS"
$PN"148"21;
"HSCL"
$PN"4"19;
"HSDA"
$PN"5"18;
"LBD||RSP_A_N"
$PN"86"171;
"LBS||RSP_B_N"
$PN"87"168;
"PAR_A"
$PN"74"120;
"PAR_B"
$PN"227"121;
"RESET_N \B"
$PN"207"23;
"RFU6"
$PN"232"0;
"RFU5"
$PN"231"0;
"RFU4"
$PN"220"0;
"RFU3"
$PN"150"0;
"RFU2"
$PN"149"0;
"RFU1"
$PN"144"0;
"RFU0"
$PN"2"0;
"VIN_MGMT"
$PN"3"15;
%"TAP"
"1","(-3475,3700)","0","mstr_standard","I220";
;
CDS_LIB"mstr_standard"
BODY_TYPE"PLUMBING"
HDL_TAP"TRUE";
"B \NAC \NWC"7;
"S \NAC"
BN"0"128;
%"TAP"
"1","(-3475,3550)","0","mstr_standard","I221";
;
CDS_LIB"mstr_standard"
BODY_TYPE"PLUMBING"
HDL_TAP"TRUE";
"B \NAC \NWC"5;
"S \NAC"
BN"9"161;
%"TAP"
"1","(-3475,3450)","0","mstr_standard","I222";
;
CDS_LIB"mstr_standard"
BODY_TYPE"PLUMBING"
HDL_TAP"TRUE";
"B \NAC \NWC"5;
"S \NAC"
BN"8"124;
%"TAP"
"1","(-3275,3300)","0","mstr_standard","I223";
;
CDS_LIB"mstr_standard"
BODY_TYPE"PLUMBING"
HDL_TAP"TRUE";
"B \NAC \NWC"6;
"S \NAC"
BN"7"155;
%"TAP"
"1","(-3275,3000)","0","mstr_standard","I224";
;
CDS_LIB"mstr_standard"
BODY_TYPE"PLUMBING"
HDL_TAP"TRUE";
"B \NAC \NWC"6;
"S \NAC"
BN"4"145;
%"TAP"
"1","(-3275,3100)","0","mstr_standard","I225";
;
CDS_LIB"mstr_standard"
BODY_TYPE"PLUMBING"
HDL_TAP"TRUE";
"B \NAC \NWC"6;
"S \NAC"
BN"5"149;
%"TAP"
"1","(-3275,2900)","0","mstr_standard","I226";
;
CDS_LIB"mstr_standard"
BODY_TYPE"PLUMBING"
HDL_TAP"TRUE";
"B \NAC \NWC"6;
"S \NAC"
BN"3"141;
%"TAP"
"1","(-3275,2800)","0","mstr_standard","I227";
;
CDS_LIB"mstr_standard"
BODY_TYPE"PLUMBING"
HDL_TAP"TRUE";
"B \NAC \NWC"6;
"S \NAC"
BN"2"137;
%"TAP"
"1","(-3275,2700)","0","mstr_standard","I228";
;
CDS_LIB"mstr_standard"
BODY_TYPE"PLUMBING"
HDL_TAP"TRUE";
"B \NAC \NWC"6;
"S \NAC"
BN"1"133;
%"TAP"
"1","(-3275,2600)","0","mstr_standard","I229";
;
CDS_LIB"mstr_standard"
BODY_TYPE"PLUMBING"
HDL_TAP"TRUE";
"B \NAC \NWC"6;
"S \NAC"
BN"0"129;
%"TAP"
"1","(-7725,3175)","2","mstr_standard","I23";
;
CDS_LIB"mstr_standard"
BODY_TYPE"PLUMBING"
HDL_TAP"TRUE";
"B \NAC \NWC"11;
"S \NAC"
BN"0"30;
%"TAP"
"1","(-3475,3150)","0","mstr_standard","I230";
;
CDS_LIB"mstr_standard"
BODY_TYPE"PLUMBING"
HDL_TAP"TRUE";
"B \NAC \NWC"5;
"S \NAC"
BN"5"150;
%"TAP"
"1","(-3475,3050)","0","mstr_standard","I231";
;
CDS_LIB"mstr_standard"
BODY_TYPE"PLUMBING"
HDL_TAP"TRUE";
"B \NAC \NWC"5;
"S \NAC"
BN"4"146;
%"TAP"
"1","(-3475,2950)","0","mstr_standard","I232";
;
CDS_LIB"mstr_standard"
BODY_TYPE"PLUMBING"
HDL_TAP"TRUE";
"B \NAC \NWC"5;
"S \NAC"
BN"3"142;
%"TAP"
"1","(-3475,2850)","0","mstr_standard","I233";
;
CDS_LIB"mstr_standard"
BODY_TYPE"PLUMBING"
HDL_TAP"TRUE";
"B \NAC \NWC"5;
"S \NAC"
BN"2"138;
%"TAP"
"1","(-3475,2750)","0","mstr_standard","I234";
;
CDS_LIB"mstr_standard"
BODY_TYPE"PLUMBING"
HDL_TAP"TRUE";
"B \NAC \NWC"5;
"S \NAC"
BN"1"134;
%"TAP"
"1","(-3475,2650)","0","mstr_standard","I235";
;
CDS_LIB"mstr_standard"
BODY_TYPE"PLUMBING"
HDL_TAP"TRUE";
"B \NAC \NWC"5;
"S \NAC"
BN"0"130;
%"SCONN288_DDR506112002KQ"
"2","(-4425,3600)","0","pure_quanta","I236";
;
LOCATION"J20"
$SEC"2"
CDS_SEC"2"
PART_TYPE"SMLF"
MATERIAL"IO"
VALUE"SCONN288_DDR506112002KQ"
CDS_LMAN_SYM_OUTLINE"-600,1150,600,-1150"
NEEDS_NO_SIZE"TRUE"
CDS_LIB"pure_quanta"
PART_NUMBER"DFHST8FS479";
"DQS7_A_C||TDQS7_A_C \B"
$PN"178"122;
"DQS6_A_T||TDQS6_A_T"
$PN"168"123;
"DQS8_B_T||TDQS8_B_T"
$PN"283"124;
"DQS8_B_C||TDQS8_B_C \B"
$PN"282"125;
"DQS7_B_T||TDQS7_B_T"
$PN"272"126;
"DQS0_A_C \B"
$PN"12"127;
"DQS0_A_T"
$PN"11"128;
"DQS0_B_C \B"
$PN"105"129;
"DQS0_B_T"
$PN"104"130;
"DQS1_A_C \B"
$PN"23"131;
"DQS1_A_T"
$PN"22"132;
"DQS1_B_C \B"
$PN"116"133;
"DQS1_B_T"
$PN"115"134;
"DQS2_A_C \B"
$PN"34"135;
"DQS2_A_T"
$PN"33"136;
"DQS2_B_C \B"
$PN"127"137;
"DQS2_B_T"
$PN"126"138;
"DQS3_A_C \B"
$PN"45"139;
"DQS3_A_T"
$PN"44"140;
"DQS3_B_C \B"
$PN"138"141;
"DQS3_B_T"
$PN"137"142;
"DQS4_A_C \B"
$PN"56"143;
"DQS4_A_T"
$PN"55"144;
"DQS4_B_C \B"
$PN"238"145;
"DQS4_B_T"
$PN"239"146;
"DQS5_A_C||TDQS5_A_C||DQS5_A_T||TDQS5_A_T \B"
$PN"156"147;
"DQS5_A_T||TDQS5_A_T"
$PN"157"148;
"DQS5_B_C||TDQS5_B_C \B"
$PN"249"149;
"DQS5_B_T||TDQS5_B_T"
$PN"250"150;
"DQS6_A_C||TDQS6_A_C||DQS6_A_T||TDQS6_A_T \B"
$PN"167"151;
"DQS6_B_C||TDQS6_B_C \B"
$PN"260"152;
"DQS6_B_T||TDQS6_B_T"
$PN"261"153;
"DQS7_A_T||TDQS7_A_T"
$PN"179"154;
"DQS7_B_C||TDQS7_B_C \B"
$PN"271"155;
"DQS8_A_C||TDQS8_A_C \B"
$PN"189"156;
"DQS8_A_T||TDQS8_A_T"
$PN"190"157;
"DQS9_A_C||TDQS9_A_C \B"
$PN"200"158;
"DQS9_A_T||TDQS9_A_T"
$PN"201"159;
"DQS9_B_C||TDQS9_B_C \B"
$PN"94"160;
"DQS9_B_T||TDQS9_B_T||DBI4_B_N"
$PN"93"161;
%"GND"
"1","(-2825,5650)","0","pure_quanta_power","I237";
;
CDS_LIB"pure_quanta_power"
BOM_COST"MEM"
SIZE"1B"
ROOM"MEM_EFGH_DECOUPLING_CAPS"
HDL_POWER"GND";
"A<SIZE-1..0>\NAC"28;
%"Q_CAP"
"1","(-2825,6000)","2","pure_quanta","I238";
;
LOCATION"C167"
$SEC"1"
CDS_SEC"1"
PACK_TYPE"C0805"
VOLTAGE"25V"
VALUE"10UF"
TOLERANCE"10%"
MATERIAL"X6S"
CDS_LIB"pure_quanta"
BOM_COST"MEM"
ROOM""
PART_NUMBER"CH6104KEA00";
"B"
$PN"2"28;
"A"
$PN"1"29;
%"Q_CAP"
"1","(-2250,6000)","2","pure_quanta","I239";
;
LOCATION"C169"
$SEC"1"
CDS_SEC"1"
PACK_TYPE"C0805"
VOLTAGE"25V"
VALUE"10UF"
TOLERANCE"10%"
MATERIAL"X6S"
CDS_LIB"pure_quanta"
BOM_COST"MEM"
ROOM""
PART_NUMBER"CH6104KEA00";
"B"
$PN"2"28;
"A"
$PN"1"29;
%"TAP"
"1","(-7725,3225)","2","mstr_standard","I24";
;
CDS_LIB"mstr_standard"
BODY_TYPE"PLUMBING"
HDL_TAP"TRUE";
"B \NAC \NWC"11;
"S \NAC"
BN"1"31;
%"UNIVERSAL_POWER"
"1","(-2825,6325)","0","pure_quanta_power","I240";
;
HDL_POWER"P12V_MEM_CPU0"
BOM_COST"VR_SYSTEM"
CDS_LIB"pure_quanta_power";
"A"29;
%"Q_RES"
"1","(-7775,2600)","0","pure_quanta","I242";
;
LOCATION"R1578"
$SEC"1"
CDS_SEC"1"
VALUE"49.9"
CDS_LIB"pure_quanta"
TOLERANCE"1%"
WATTAGE"1/16W"
PACK_TYPE"0402LF"
MATERIAL"CHIP"
PART_NUMBER"CS04992FB07";
"B"
$PN"2"19;
"A"
$PN"1"16;
%"Q_RES"
"1","(-8175,2825)","0","pure_quanta","I243";
;
LOCATION"R1685"
$SEC"1"
CDS_SEC"1"
PACK_TYPE"0402LF"
VALUE"10"
MATERIAL"CHIP"
CDS_LIB"pure_quanta"
TOLERANCE"1%"
WATTAGE"1/16W"
PART_NUMBER"CS01002FB07";
"B"
$PN"2"18;
"A"
$PN"1"17;
%"TAP"
"1","(-7725,3275)","2","mstr_standard","I25";
;
CDS_LIB"mstr_standard"
BODY_TYPE"PLUMBING"
HDL_TAP"TRUE";
"B \NAC \NWC"11;
"S \NAC"
BN"2"14;
%"TAP"
"1","(-7725,3375)","2","mstr_standard","I26";
;
CDS_LIB"mstr_standard"
BODY_TYPE"PLUMBING"
HDL_TAP"TRUE";
"B \NAC \NWC"11;
"S \NAC"
BN"4"32;
%"TAP"
"1","(-7725,3325)","2","mstr_standard","I27";
;
CDS_LIB"mstr_standard"
BODY_TYPE"PLUMBING"
HDL_TAP"TRUE";
"B \NAC \NWC"11;
"S \NAC"
BN"3"56;
%"TAP"
"1","(-7725,3425)","2","mstr_standard","I28";
;
CDS_LIB"mstr_standard"
BODY_TYPE"PLUMBING"
HDL_TAP"TRUE";
"B \NAC \NWC"11;
"S \NAC"
BN"5"33;
%"TAP"
"1","(-7725,3475)","2","mstr_standard","I29";
;
CDS_LIB"mstr_standard"
BODY_TYPE"PLUMBING"
HDL_TAP"TRUE";
"B \NAC \NWC"11;
"S \NAC"
BN"6"55;
%"TAP"
"1","(-7725,3525)","2","mstr_standard","I30";
;
CDS_LIB"mstr_standard"
BODY_TYPE"PLUMBING"
HDL_TAP"TRUE";
"B \NAC \NWC"11;
"S \NAC"
BN"7"40;
%"TAP"
"1","(-7725,3625)","2","mstr_standard","I31";
;
CDS_LIB"mstr_standard"
BODY_TYPE"PLUMBING"
HDL_TAP"TRUE";
"B \NAC \NWC"12;
"S \NAC"
BN"0"34;
%"TAP"
"1","(-7725,3675)","2","mstr_standard","I32";
;
CDS_LIB"mstr_standard"
BODY_TYPE"PLUMBING"
HDL_TAP"TRUE";
"B \NAC \NWC"12;
"S \NAC"
BN"1"39;
%"TAP"
"1","(-7725,3725)","2","mstr_standard","I33";
;
CDS_LIB"mstr_standard"
BODY_TYPE"PLUMBING"
HDL_TAP"TRUE";
"B \NAC \NWC"12;
"S \NAC"
BN"2"54;
%"TAP"
"1","(-7725,3775)","2","mstr_standard","I34";
;
CDS_LIB"mstr_standard"
BODY_TYPE"PLUMBING"
HDL_TAP"TRUE";
"B \NAC \NWC"12;
"S \NAC"
BN"3"53;
%"TAP"
"1","(-7725,3875)","2","mstr_standard","I35";
;
CDS_LIB"mstr_standard"
BODY_TYPE"PLUMBING"
HDL_TAP"TRUE";
"B \NAC \NWC"12;
"S \NAC"
BN"5"52;
%"TAP"
"1","(-7725,3825)","2","mstr_standard","I36";
;
CDS_LIB"mstr_standard"
BODY_TYPE"PLUMBING"
HDL_TAP"TRUE";
"B \NAC \NWC"12;
"S \NAC"
BN"4"38;
%"TAP"
"1","(-6025,2175)","0","mstr_standard","I37";
;
CDS_LIB"mstr_standard"
BODY_TYPE"PLUMBING"
HDL_TAP"TRUE";
"B \NAC \NWC"9;
"S \NAC"
BN"0"119;
%"TAP"
"1","(-6025,2225)","0","mstr_standard","I38";
;
CDS_LIB"mstr_standard"
BODY_TYPE"PLUMBING"
HDL_TAP"TRUE";
"B \NAC \NWC"9;
"S \NAC"
BN"1"118;
%"TAP"
"1","(-6025,2275)","0","mstr_standard","I39";
;
CDS_LIB"mstr_standard"
BODY_TYPE"PLUMBING"
HDL_TAP"TRUE";
"B \NAC \NWC"9;
"S \NAC"
BN"2"117;
%"TAP"
"1","(-6025,2325)","0","mstr_standard","I40";
;
CDS_LIB"mstr_standard"
BODY_TYPE"PLUMBING"
HDL_TAP"TRUE";
"B \NAC \NWC"9;
"S \NAC"
BN"3"116;
%"TAP"
"1","(-6025,2375)","0","mstr_standard","I41";
;
CDS_LIB"mstr_standard"
BODY_TYPE"PLUMBING"
HDL_TAP"TRUE";
"B \NAC \NWC"9;
"S \NAC"
BN"4"115;
%"TAP"
"1","(-6025,2475)","0","mstr_standard","I42";
;
CDS_LIB"mstr_standard"
BODY_TYPE"PLUMBING"
HDL_TAP"TRUE";
"B \NAC \NWC"9;
"S \NAC"
BN"6"113;
%"TAP"
"1","(-6025,2425)","0","mstr_standard","I43";
;
CDS_LIB"mstr_standard"
BODY_TYPE"PLUMBING"
HDL_TAP"TRUE";
"B \NAC \NWC"9;
"S \NAC"
BN"5"114;
%"TAP"
"1","(-6025,2575)","0","mstr_standard","I44";
;
CDS_LIB"mstr_standard"
BODY_TYPE"PLUMBING"
HDL_TAP"TRUE";
"B \NAC \NWC"9;
"S \NAC"
BN"8"111;
%"TAP"
"1","(-6025,2525)","0","mstr_standard","I45";
;
CDS_LIB"mstr_standard"
BODY_TYPE"PLUMBING"
HDL_TAP"TRUE";
"B \NAC \NWC"9;
"S \NAC"
BN"7"112;
%"TAP"
"1","(-6025,2625)","0","mstr_standard","I46";
;
CDS_LIB"mstr_standard"
BODY_TYPE"PLUMBING"
HDL_TAP"TRUE";
"B \NAC \NWC"9;
"S \NAC"
BN"9"110;
%"TAP"
"1","(-6025,2725)","0","mstr_standard","I47";
;
CDS_LIB"mstr_standard"
BODY_TYPE"PLUMBING"
HDL_TAP"TRUE";
"B \NAC \NWC"9;
"S \NAC"
BN"11"108;
%"TAP"
"1","(-6025,2675)","0","mstr_standard","I48";
;
CDS_LIB"mstr_standard"
BODY_TYPE"PLUMBING"
HDL_TAP"TRUE";
"B \NAC \NWC"9;
"S \NAC"
BN"10"109;
%"TAP"
"1","(-6025,2775)","0","mstr_standard","I49";
;
CDS_LIB"mstr_standard"
BODY_TYPE"PLUMBING"
HDL_TAP"TRUE";
"B \NAC \NWC"9;
"S \NAC"
BN"12"107;
%"TAP"
"1","(-6025,2825)","0","mstr_standard","I50";
;
CDS_LIB"mstr_standard"
BODY_TYPE"PLUMBING"
HDL_TAP"TRUE";
"B \NAC \NWC"9;
"S \NAC"
BN"13"106;
%"TAP"
"1","(-6025,2875)","0","mstr_standard","I51";
;
CDS_LIB"mstr_standard"
BODY_TYPE"PLUMBING"
HDL_TAP"TRUE";
"B \NAC \NWC"9;
"S \NAC"
BN"14"105;
%"TAP"
"1","(-6025,2975)","0","mstr_standard","I52";
;
CDS_LIB"mstr_standard"
BODY_TYPE"PLUMBING"
HDL_TAP"TRUE";
"B \NAC \NWC"9;
"S \NAC"
BN"16"103;
%"TAP"
"1","(-6025,2925)","0","mstr_standard","I53";
;
CDS_LIB"mstr_standard"
BODY_TYPE"PLUMBING"
HDL_TAP"TRUE";
"B \NAC \NWC"9;
"S \NAC"
BN"15"104;
%"TAP"
"1","(-6025,3025)","0","mstr_standard","I54";
;
CDS_LIB"mstr_standard"
BODY_TYPE"PLUMBING"
HDL_TAP"TRUE";
"B \NAC \NWC"9;
"S \NAC"
BN"17"102;
%"TAP"
"1","(-6025,3075)","0","mstr_standard","I55";
;
CDS_LIB"mstr_standard"
BODY_TYPE"PLUMBING"
HDL_TAP"TRUE";
"B \NAC \NWC"9;
"S \NAC"
BN"18"101;
%"TAP"
"1","(-6025,3125)","0","mstr_standard","I56";
;
CDS_LIB"mstr_standard"
BODY_TYPE"PLUMBING"
HDL_TAP"TRUE";
"B \NAC \NWC"9;
"S \NAC"
BN"19"100;
%"TAP"
"1","(-6025,3175)","0","mstr_standard","I57";
;
CDS_LIB"mstr_standard"
BODY_TYPE"PLUMBING"
HDL_TAP"TRUE";
"B \NAC \NWC"9;
"S \NAC"
BN"20"99;
%"TAP"
"1","(-6025,3225)","0","mstr_standard","I58";
;
CDS_LIB"mstr_standard"
BODY_TYPE"PLUMBING"
HDL_TAP"TRUE";
"B \NAC \NWC"9;
"S \NAC"
BN"21"98;
%"TAP"
"1","(-6025,3275)","0","mstr_standard","I59";
;
CDS_LIB"mstr_standard"
BODY_TYPE"PLUMBING"
HDL_TAP"TRUE";
"B \NAC \NWC"9;
"S \NAC"
BN"22"97;
%"TAP"
"1","(-6025,3375)","0","mstr_standard","I60";
;
CDS_LIB"mstr_standard"
BODY_TYPE"PLUMBING"
HDL_TAP"TRUE";
"B \NAC \NWC"9;
"S \NAC"
BN"24"95;
%"TAP"
"1","(-6025,3325)","0","mstr_standard","I61";
;
CDS_LIB"mstr_standard"
BODY_TYPE"PLUMBING"
HDL_TAP"TRUE";
"B \NAC \NWC"9;
"S \NAC"
BN"23"96;
%"TAP"
"1","(-6025,3425)","0","mstr_standard","I62";
;
CDS_LIB"mstr_standard"
BODY_TYPE"PLUMBING"
HDL_TAP"TRUE";
"B \NAC \NWC"9;
"S \NAC"
BN"25"24;
%"TAP"
"1","(-6025,3475)","0","mstr_standard","I63";
;
CDS_LIB"mstr_standard"
BODY_TYPE"PLUMBING"
HDL_TAP"TRUE";
"B \NAC \NWC"9;
"S \NAC"
BN"26"94;
%"TAP"
"1","(-6025,3525)","0","mstr_standard","I64";
;
CDS_LIB"mstr_standard"
BODY_TYPE"PLUMBING"
HDL_TAP"TRUE";
"B \NAC \NWC"9;
"S \NAC"
BN"27"25;
%"TAP"
"1","(-6025,3625)","0","mstr_standard","I65";
;
CDS_LIB"mstr_standard"
BODY_TYPE"PLUMBING"
HDL_TAP"TRUE";
"B \NAC \NWC"9;
"S \NAC"
BN"29"92;
%"TAP"
"1","(-6025,3575)","0","mstr_standard","I66";
;
CDS_LIB"mstr_standard"
BODY_TYPE"PLUMBING"
HDL_TAP"TRUE";
"B \NAC \NWC"9;
"S \NAC"
BN"28"93;
%"TAP"
"1","(-6025,3725)","0","mstr_standard","I67";
;
CDS_LIB"mstr_standard"
BODY_TYPE"PLUMBING"
HDL_TAP"TRUE";
"B \NAC \NWC"9;
"S \NAC"
BN"31"90;
%"TAP"
"1","(-6025,3675)","0","mstr_standard","I68";
;
CDS_LIB"mstr_standard"
BODY_TYPE"PLUMBING"
HDL_TAP"TRUE";
"B \NAC \NWC"9;
"S \NAC"
BN"30"91;
%"TAP"
"1","(-6025,3825)","0","mstr_standard","I69";
;
CDS_LIB"mstr_standard"
BODY_TYPE"PLUMBING"
HDL_TAP"TRUE";
"B \NAC \NWC"10;
"S \NAC"
BN"0"89;
%"TAP"
"1","(-6025,3875)","0","mstr_standard","I70";
;
CDS_LIB"mstr_standard"
BODY_TYPE"PLUMBING"
HDL_TAP"TRUE";
"B \NAC \NWC"10;
"S \NAC"
BN"1"88;
%"TAP"
"1","(-7725,3925)","2","mstr_standard","I80";
;
CDS_LIB"mstr_standard"
BODY_TYPE"PLUMBING"
HDL_TAP"TRUE";
"B \NAC \NWC"12;
"S \NAC"
BN"6"51;
%"TAP"
"1","(-7725,3975)","2","mstr_standard","I81";
;
CDS_LIB"mstr_standard"
BODY_TYPE"PLUMBING"
HDL_TAP"TRUE";
"B \NAC \NWC"12;
"S \NAC"
BN"7"37;
%"TAP"
"1","(-7725,4675)","2","mstr_standard","I82";
;
CDS_LIB"mstr_standard"
BODY_TYPE"PLUMBING"
HDL_TAP"TRUE";
"B \NAC \NWC"13;
"S \NAC"
BN"0"42;
%"TAP"
"1","(-7725,4775)","2","mstr_standard","I83";
;
CDS_LIB"mstr_standard"
BODY_TYPE"PLUMBING"
HDL_TAP"TRUE";
"B \NAC \NWC"13;
"S \NAC"
BN"2"46;
%"TAP"
"1","(-7725,4725)","2","mstr_standard","I84";
;
CDS_LIB"mstr_standard"
BODY_TYPE"PLUMBING"
HDL_TAP"TRUE";
"B \NAC \NWC"13;
"S \NAC"
BN"1"44;
%"TAP"
"1","(-7725,4875)","2","mstr_standard","I85";
;
CDS_LIB"mstr_standard"
BODY_TYPE"PLUMBING"
HDL_TAP"TRUE";
"B \NAC \NWC"13;
"S \NAC"
BN"4"48;
%"TAP"
"1","(-7725,4825)","2","mstr_standard","I86";
;
CDS_LIB"mstr_standard"
BODY_TYPE"PLUMBING"
HDL_TAP"TRUE";
"B \NAC \NWC"13;
"S \NAC"
BN"3"47;
%"TAP"
"1","(-7725,4925)","2","mstr_standard","I87";
;
CDS_LIB"mstr_standard"
BODY_TYPE"PLUMBING"
HDL_TAP"TRUE";
"B \NAC \NWC"13;
"S \NAC"
BN"5"49;
%"TAP"
"1","(-7725,4975)","2","mstr_standard","I88";
;
CDS_LIB"mstr_standard"
BODY_TYPE"PLUMBING"
HDL_TAP"TRUE";
"B \NAC \NWC"13;
"S \NAC"
BN"6"50;
%"TAP"
"1","(-7725,5075)","2","mstr_standard","I89";
;
CDS_LIB"mstr_standard"
BODY_TYPE"PLUMBING"
HDL_TAP"TRUE";
"B \NAC \NWC"4;
"S \NAC"
BN"0"41;
%"VCC_CORE"
"1","(-8500,3400)","0","mstr_symbols","I9";
;
HDL_POWER"P3V3_AUX"
CDS_LIB"mstr_symbols"
VOLTAGE"3.3"
ROOM"PVCCINFAON_CPU0_CTRL";
"A"15;
%"TAP"
"1","(-7725,5125)","2","mstr_standard","I90";
;
CDS_LIB"mstr_standard"
BODY_TYPE"PLUMBING"
HDL_TAP"TRUE";
"B \NAC \NWC"4;
"S \NAC"
BN"1"43;
%"TAP"
"1","(-7725,5175)","2","mstr_standard","I91";
;
CDS_LIB"mstr_standard"
BODY_TYPE"PLUMBING"
HDL_TAP"TRUE";
"B \NAC \NWC"4;
"S \NAC"
BN"2"45;
%"TAP"
"1","(-7725,5225)","2","mstr_standard","I92";
;
CDS_LIB"mstr_standard"
BODY_TYPE"PLUMBING"
HDL_TAP"TRUE";
"B \NAC \NWC"4;
"S \NAC"
BN"3"162;
%"TAP"
"1","(-7725,5275)","2","mstr_standard","I93";
;
CDS_LIB"mstr_standard"
BODY_TYPE"PLUMBING"
HDL_TAP"TRUE";
"B \NAC \NWC"4;
"S \NAC"
BN"4"163;
%"TAP"
"1","(-7725,5325)","2","mstr_standard","I94";
;
CDS_LIB"mstr_standard"
BODY_TYPE"PLUMBING"
HDL_TAP"TRUE";
"B \NAC \NWC"4;
"S \NAC"
BN"5"164;
%"TAP"
"1","(-7725,5375)","2","mstr_standard","I95";
;
CDS_LIB"mstr_standard"
BODY_TYPE"PLUMBING"
HDL_TAP"TRUE";
"B \NAC \NWC"4;
"S \NAC"
BN"6"165;
%"TAP"
"1","(-6025,3925)","0","mstr_standard","I96";
;
CDS_LIB"mstr_standard"
BODY_TYPE"PLUMBING"
HDL_TAP"TRUE";
"B \NAC \NWC"10;
"S \NAC"
BN"2"87;
%"TAP"
"1","(-6025,3975)","0","mstr_standard","I97";
;
CDS_LIB"mstr_standard"
BODY_TYPE"PLUMBING"
HDL_TAP"TRUE";
"B \NAC \NWC"10;
"S \NAC"
BN"3"86;
%"TAP"
"1","(-6025,4025)","0","mstr_standard","I98";
;
CDS_LIB"mstr_standard"
BODY_TYPE"PLUMBING"
HDL_TAP"TRUE";
"B \NAC \NWC"10;
"S \NAC"
BN"4"85;
%"TAP"
"1","(-6025,4075)","0","mstr_standard","I99";
;
CDS_LIB"mstr_standard"
BODY_TYPE"PLUMBING"
HDL_TAP"TRUE";
"B \NAC \NWC"10;
"S \NAC"
BN"5"84;
END.
